# T6G (Grand Teton) — schematic netlist excerpt (pin names and nets, part order shuffled) for the footprints in the layout excerpt that follows; sources: Cadence DE-HDL packaged netlist, KiCad conversion of 04192023_DAF0TMB3IC0_F0TG_MB_C_brd_V02_OCP.brd

C143  Q_CAP  10UF 25V 10% X6S  pkg C0805  page 87 : A = P12V_MEM_CPU0 ; B = GND
PC93_2  Q_CAP  22UF 16V 20% X6S  pkg C0805  page 201 : A = SW_P12V_AUX_PVDDCR_CPU1_P0_FLT ; B = GND
R1246  Q_RES  0 5% EMPTY  pkg 0402LF  page 258 : A = P1V8_CPU0_RT_1D_ADC ; B = P1V8_CPU0_RT_1D_ADC_MAM

(kicad_pcb
	(version 20260206)
	(generator "pcbnew")
	(generator_version "10.0")
	(general
		(thickness 1.6)
		(legacy_teardrops no)
	)
	(paper "A4")
	(title_block
		(title "04192023_DAF0TMB3IC0_F0TG_MB_C_brd_V02_OCP.brd")
		(comment 1 "Grand Teton / footprints 5502-5504 of 8354")
	)
	(layers
		(0 "F.Cu" signal "TOP")
		(4 "In1.Cu" signal "GND")
		(6 "In2.Cu" signal "IN1")
		(8 "In3.Cu" signal "GND1")
		(10 "In4.Cu" signal "IN2")
		(12 "In5.Cu" signal "GND2")
		(14 "In6.Cu" signal "IN3")
		(16 "In7.Cu" signal "GND3")
		(18 "In8.Cu" signal "VCC")
		(20 "In9.Cu" signal "VCC1")
		(22 "In10.Cu" signal "GND4")
		(24 "In11.Cu" signal "IN4")
		(26 "In12.Cu" signal "GND5")
		(28 "In13.Cu" signal "IN5")
		(30 "In14.Cu" signal "GND6")
		(32 "In15.Cu" signal "IN6")
		(34 "In16.Cu" signal "GND7")
		(2 "B.Cu" signal "BOTTOM")
		(9 "F.Adhes" user "F.Adhesive")
		(11 "B.Adhes" user "B.Adhesive")
		(13 "F.Paste" user "Package Geometry/Pastemask Top")
		(15 "B.Paste" user "Package Geometry/Pastemask Bottom")
		(5 "F.SilkS" user "Ref Des/Silkscreen Top")
		(7 "B.SilkS" user "Ref Des/Silkscreen Bottom")
		(1 "F.Mask" user "Board Geometry/Soldermask Top")
		(3 "B.Mask" user "Board Geometry/Soldermask Bottom")
		(17 "Dwgs.User" user "User.Drawings")
		(19 "Cmts.User" user "User.Comments")
		(21 "Eco1.User" user "User.Eco1")
		(23 "Eco2.User" user "User.Eco2")
		(25 "Edge.Cuts" user "Board Geometry/Outline")
		(27 "Margin" user)
		(31 "F.CrtYd" user "Package Geometry/Place Bound Top")
		(29 "B.CrtYd" user "Package Geometry/Place Bound Bottom")
		(35 "F.Fab" user "Ref Des/Assembly Top")
		(33 "B.Fab" user "Ref Des/Assembly Bottom")
	)
	(footprint ""
		(layer "B.Cu")
		(at 231.882696 -324.980554 180)
		(property "Reference" "R1246"
			(at 0 0 0)
			(layer "B.SilkS")
			(hide yes)
			(effects
				(font
					(size 1.27 1.27)
				)
				(justify mirror)
			)
		)
		(property "Value" ""
			(at 0 0 0)
			(layer "B.Fab")
			(effects
				(font
					(size 1.27 1.27)
				)
				(justify mirror)
			)
		)
		(duplicate_pad_numbers_are_jumpers no)
		(fp_line
			(start 0.7874 0.4064)
			(end 0.7874 -0.4064)
			(stroke
				(width 0.1524)
				(type default)
			)
			(layer "B.SilkS")
		)
		(fp_line
			(start 0.7874 -0.4064)
			(end -0.7874 -0.4064)
			(stroke
				(width 0.1524)
				(type default)
			)
			(layer "B.SilkS")
		)
		(fp_line
			(start -0.7874 0.4064)
			(end 0.7874 0.4064)
			(stroke
				(width 0.1524)
				(type default)
			)
			(layer "B.SilkS")
		)
		(fp_line
			(start -0.7874 -0.4064)
			(end -0.7874 0.4064)
			(stroke
				(width 0.1524)
				(type default)
			)
			(layer "B.SilkS")
		)
		(fp_line
			(start 0.67945 0.3048)
			(end 0.67945 -0.305054)
			(stroke
				(width 0.1)
				(type default)
			)
			(layer "B.Fab")
		)
		(fp_line
			(start 0.67945 -0.305054)
			(end 0.12065 -0.305054)
			(stroke
				(width 0.1)
				(type default)
			)
			(layer "B.Fab")
		)
		(fp_line
			(start 0.12065 0.3048)
			(end 0.67945 0.3048)
			(stroke
				(width 0.1)
				(type default)
			)
			(layer "B.Fab")
		)
		(fp_line
			(start 0.12065 0.2794)
			(end 0.12065 0.3048)
			(stroke
				(width 0.1)
				(type default)
			)
			(layer "B.Fab")
		)
		(fp_line
			(start 0.12065 -0.2794)
			(end -0.12065 -0.2794)
			(stroke
				(width 0.1)
				(type default)
			)
			(layer "B.Fab")
		)
		(fp_line
			(start 0.12065 -0.305054)
			(end 0.12065 -0.2794)
			(stroke
				(width 0.1)
				(type default)
			)
			(layer "B.Fab")
		)
		(fp_line
			(start -0.120396 0.3048)
			(end -0.120396 0.2794)
			(stroke
				(width 0.1)
				(type default)
			)
			(layer "B.Fab")
		)
		(fp_line
			(start -0.120396 0.2794)
			(end 0.12065 0.2794)
			(stroke
				(width 0.1)
				(type default)
			)
			(layer "B.Fab")
		)
		(fp_line
			(start -0.12065 -0.2794)
			(end -0.12065 -0.3048)
			(stroke
				(width 0.1)
				(type default)
			)
			(layer "B.Fab")
		)
		(fp_line
			(start -0.12065 -0.3048)
			(end -0.67945 -0.3048)
			(stroke
				(width 0.1)
				(type default)
			)
			(layer "B.Fab")
		)
		(fp_line
			(start -0.67945 0.3048)
			(end -0.120396 0.3048)
			(stroke
				(width 0.1)
				(type default)
			)
			(layer "B.Fab")
		)
		(fp_line
			(start -0.67945 -0.3048)
			(end -0.67945 0.3048)
			(stroke
				(width 0.1)
				(type default)
			)
			(layer "B.Fab")
		)
		(pad "1" smd rect
			(at 0.40005 0 180)
			(size 0.4572 0.508)
			(layers "B.Cu" "B.Mask" "B.Paste")
			(net "P1V8_CPU0_RT_1D_ADC")
		)
		(pad "2" smd rect
			(at -0.40005 0 180)
			(size 0.4572 0.508)
			(layers "B.Cu" "B.Mask" "B.Paste")
			(net "P1V8_CPU0_RT_1D_ADC_MAM")
		)
	)
	(footprint ""
		(layer "B.Cu")
		(at 327.823068 -338.927694 -90)
		(property "Reference" "PC93_2"
			(at 0 0 90)
			(layer "B.SilkS")
			(hide yes)
			(effects
				(font
					(size 1.27 1.27)
				)
				(justify mirror)
			)
		)
		(property "Value" ""
			(at 0 0 90)
			(layer "B.Fab")
			(effects
				(font
					(size 1.27 1.27)
				)
				(justify mirror)
			)
		)
		(duplicate_pad_numbers_are_jumpers no)
		(fp_line
			(start -1.524 0.762)
			(end 1.524 0.762)
			(stroke
				(width 0.1524)
				(type default)
			)
			(layer "B.SilkS")
		)
		(fp_line
			(start 1.524 0.762)
			(end 1.524 -0.762)
			(stroke
				(width 0.1524)
				(type default)
			)
			(layer "B.SilkS")
		)
		(fp_line
			(start -1.524 -0.762)
			(end -1.524 0.762)
			(stroke
				(width 0.1524)
				(type default)
			)
			(layer "B.SilkS")
		)
		(fp_line
			(start 1.524 -0.762)
			(end -1.524 -0.762)
			(stroke
				(width 0.1524)
				(type default)
			)
			(layer "B.SilkS")
		)
		(fp_line
			(start -1.1049 0.724916)
			(end -1.1049 -0.724916)
			(stroke
				(width 0.1)
				(type default)
			)
			(layer "B.Fab")
		)
		(fp_line
			(start 1.1049 0.724916)
			(end -1.1049 0.724916)
			(stroke
				(width 0.1)
				(type default)
			)
			(layer "B.Fab")
		)
		(fp_line
			(start -1.1049 -0.724916)
			(end 1.1049 -0.724916)
			(stroke
				(width 0.1)
				(type default)
			)
			(layer "B.Fab")
		)
		(fp_line
			(start 1.1049 -0.724916)
			(end 1.1049 0.724916)
			(stroke
				(width 0.1)
				(type default)
			)
			(layer "B.Fab")
		)
		(pad "1" smd rect
			(at 0.889 0 270)
			(size 1.016 1.27)
			(layers "B.Cu" "B.Mask" "B.Paste")
			(net "SW_P12V_AUX_PVDDCR_CPU1_P0_FLT")
		)
		(pad "2" smd rect
			(at -0.889 0 270)
			(size 1.016 1.27)
			(layers "B.Cu" "B.Mask" "B.Paste")
			(net "GND")
		)
	)
	(footprint ""
		(layer "B.Cu")
		(at 299.82414 -192.660016)
		(property "Reference" "C143"
			(at 0 0 0)
			(layer "B.SilkS")
			(hide yes)
			(effects
				(font
					(size 1.27 1.27)
				)
				(justify mirror)
			)
		)
		(property "Value" ""
			(at 0 0 0)
			(layer "B.Fab")
			(effects
				(font
					(size 1.27 1.27)
				)
				(justify mirror)
			)
		)
		(duplicate_pad_numbers_are_jumpers no)
		(fp_line
			(start -1.524 -0.762)
			(end -1.524 0.762)
			(stroke
				(width 0.1524)
				(type default)
			)
			(layer "B.SilkS")
		)
		(fp_line
			(start -1.524 0.762)
			(end 1.524 0.762)
			(stroke
				(width 0.1524)
				(type default)
			)
			(layer "B.SilkS")
		)
		(fp_line
			(start 1.524 -0.762)
			(end -1.524 -0.762)
			(stroke
				(width 0.1524)
				(type default)
			)
			(layer "B.SilkS")
		)
		(fp_line
			(start 1.524 0.762)
			(end 1.524 -0.762)
			(stroke
				(width 0.1524)
				(type default)
			)
			(layer "B.SilkS")
		)
		(fp_line
			(start -1.1049 -0.724916)
			(end 1.1049 -0.724916)
			(stroke
				(width 0.1)
				(type default)
			)
			(layer "B.Fab")
		)
		(fp_line
			(start -1.1049 0.724916)
			(end -1.1049 -0.724916)
			(stroke
				(width 0.1)
				(type default)
			)
			(layer "B.Fab")
		)
		(fp_line
			(start 1.1049 -0.724916)
			(end 1.1049 0.724916)
			(stroke
				(width 0.1)
				(type default)
			)
			(layer "B.Fab")
		)
		(fp_line
			(start 1.1049 0.724916)
			(end -1.1049 0.724916)
			(stroke
				(width 0.1)
				(type default)
			)
			(layer "B.Fab")
		)
		(pad "1" smd rect
			(at 0.889 0)
			(size 1.016 1.27)
			(layers "B.Cu" "B.Mask" "B.Paste")
			(net "P12V_MEM_CPU0")
		)
		(pad "2" smd rect
			(at -0.889 0)
			(size 1.016 1.27)
			(layers "B.Cu" "B.Mask" "B.Paste")
			(net "GND")
		)
	)
)
